(kicad_pcb
	(version 20260206)
	(generator "pcbnew")
	(generator_version "10.0")
	(general
		(thickness 1.6)
		(legacy_teardrops no)
	)
	(paper "A4")
	(title_block
		(title "04192023_DAF0TMB3IC0_F0TG_MB_C_brd_V02_OCP.brd")
		(comment 1 "Grand Teton / footprints 7493-7498 of 8354")
	)
	(layers
		(0 "F.Cu" signal "TOP")
		(4 "In1.Cu" signal "GND")
		(6 "In2.Cu" signal "IN1")
		(8 "In3.Cu" signal "GND1")
		(10 "In4.Cu" signal "IN2")
		(12 "In5.Cu" signal "GND2")
		(14 "In6.Cu" signal "IN3")
		(16 "In7.Cu" signal "GND3")
		(18 "In8.Cu" signal "VCC")
		(20 "In9.Cu" signal "VCC1")
		(22 "In10.Cu" signal "GND4")
		(24 "In11.Cu" signal "IN4")
		(26 "In12.Cu" signal "GND5")
		(28 "In13.Cu" signal "IN5")
		(30 "In14.Cu" signal "GND6")
		(32 "In15.Cu" signal "IN6")
		(34 "In16.Cu" signal "GND7")
		(2 "B.Cu" signal "BOTTOM")
		(9 "F.Adhes" user "F.Adhesive")
		(11 "B.Adhes" user "B.Adhesive")
		(13 "F.Paste" user "Package Geometry/Pastemask Top")
		(15 "B.Paste" user "Package Geometry/Pastemask Bottom")
		(5 "F.SilkS" user "Ref Des/Silkscreen Top")
		(7 "B.SilkS" user "Ref Des/Silkscreen Bottom")
		(1 "F.Mask" user "Board Geometry/Soldermask Top")
		(3 "B.Mask" user "Board Geometry/Soldermask Bottom")
		(17 "Dwgs.User" user "User.Drawings")
		(19 "Cmts.User" user "User.Comments")
		(21 "Eco1.User" user "User.Eco1")
		(23 "Eco2.User" user "User.Eco2")
		(25 "Edge.Cuts" user "Board Geometry/Outline")
		(27 "Margin" user)
		(31 "F.CrtYd" user "Package Geometry/Place Bound Top")
		(29 "B.CrtYd" user "Package Geometry/Place Bound Bottom")
		(35 "F.Fab" user "Ref Des/Assembly Top")
		(33 "B.Fab" user "Ref Des/Assembly Bottom")
	)
	(footprint ""
		(layer "B.Cu")
		(at 377.234958 -205.101952 -90)
		(property "Reference" "R403"
			(at 0 0 90)
			(layer "B.SilkS")
			(hide yes)
			(effects
				(font
					(size 1.27 1.27)
				)
				(justify mirror)
			)
		)
		(property "Value" ""
			(at 0 0 90)
			(layer "B.Fab")
			(effects
				(font
					(size 1.27 1.27)
				)
				(justify mirror)
			)
		)
		(duplicate_pad_numbers_are_jumpers no)
		(fp_line
			(start -0.7874 0.4064)
			(end 0.7874 0.4064)
			(stroke
				(width 0.1524)
				(type default)
			)
			(layer "B.SilkS")
		)
		(fp_line
			(start 0.7874 0.4064)
			(end 0.7874 -0.4064)
			(stroke
				(width 0.1524)
				(type default)
			)
			(layer "B.SilkS")
		)
		(fp_line
			(start -0.7874 -0.4064)
			(end -0.7874 0.4064)
			(stroke
				(width 0.1524)
				(type default)
			)
			(layer "B.SilkS")
		)
		(fp_line
			(start 0.7874 -0.4064)
			(end -0.7874 -0.4064)
			(stroke
				(width 0.1524)
				(type default)
			)
			(layer "B.SilkS")
		)
		(fp_line
			(start -0.67945 0.3048)
			(end -0.120396 0.3048)
			(stroke
				(width 0.1)
				(type default)
			)
			(layer "B.Fab")
		)
		(fp_line
			(start -0.120396 0.3048)
			(end -0.120396 0.2794)
			(stroke
				(width 0.1)
				(type default)
			)
			(layer "B.Fab")
		)
		(fp_line
			(start 0.12065 0.3048)
			(end 0.67945 0.3048)
			(stroke
				(width 0.1)
				(type default)
			)
			(layer "B.Fab")
		)
		(fp_line
			(start 0.67945 0.3048)
			(end 0.67945 -0.305054)
			(stroke
				(width 0.1)
				(type default)
			)
			(layer "B.Fab")
		)
		(fp_line
			(start -0.120396 0.2794)
			(end 0.12065 0.2794)
			(stroke
				(width 0.1)
				(type default)
			)
			(layer "B.Fab")
		)
		(fp_line
			(start 0.12065 0.2794)
			(end 0.12065 0.3048)
			(stroke
				(width 0.1)
				(type default)
			)
			(layer "B.Fab")
		)
		(fp_line
			(start -0.12065 -0.2794)
			(end -0.12065 -0.3048)
			(stroke
				(width 0.1)
				(type default)
			)
			(layer "B.Fab")
		)
		(fp_line
			(start 0.12065 -0.2794)
			(end -0.12065 -0.2794)
			(stroke
				(width 0.1)
				(type default)
			)
			(layer "B.Fab")
		)
		(fp_line
			(start -0.67945 -0.3048)
			(end -0.67945 0.3048)
			(stroke
				(width 0.1)
				(type default)
			)
			(layer "B.Fab")
		)
		(fp_line
			(start -0.12065 -0.3048)
			(end -0.67945 -0.3048)
			(stroke
				(width 0.1)
				(type default)
			)
			(layer "B.Fab")
		)
		(fp_line
			(start 0.12065 -0.305054)
			(end 0.12065 -0.2794)
			(stroke
				(width 0.1)
				(type default)
			)
			(layer "B.Fab")
		)
		(fp_line
			(start 0.67945 -0.305054)
			(end 0.12065 -0.305054)
			(stroke
				(width 0.1)
				(type default)
			)
			(layer "B.Fab")
		)
		(pad "1" smd circle
			(at 0.40005 0 90)
			(size 0 0)
			(layers "B.Cu" "B.Mask" "B.Paste")
			(net "PVDD18_S5_P0")
		)
		(pad "2" smd circle
			(at -0.40005 0 90)
			(size 0 0)
			(layers "B.Cu" "B.Mask" "B.Paste")
			(net "JTAG_CPU0_DBREQ_N")
		)
	)
	(footprint ""
		(layer "B.Cu")
		(at 104.850946 -340.007194 90)
		(property "Reference" "PC144_6"
			(at 0 0 90)
			(layer "B.SilkS")
			(hide yes)
			(effects
				(font
					(size 1.27 1.27)
				)
				(justify mirror)
			)
		)
		(property "Value" ""
			(at 0 0 90)
			(layer "B.Fab")
			(effects
				(font
					(size 1.27 1.27)
				)
				(justify mirror)
			)
		)
		(duplicate_pad_numbers_are_jumpers no)
		(fp_line
			(start 1.524 -0.762)
			(end -1.524 -0.762)
			(stroke
				(width 0.1524)
				(type default)
			)
			(layer "B.SilkS")
		)
		(fp_line
			(start -1.524 -0.762)
			(end -1.524 0.762)
			(stroke
				(width 0.1524)
				(type default)
			)
			(layer "B.SilkS")
		)
		(fp_line
			(start 1.524 0.762)
			(end 1.524 -0.762)
			(stroke
				(width 0.1524)
				(type default)
			)
			(layer "B.SilkS")
		)
		(fp_line
			(start -1.524 0.762)
			(end 1.524 0.762)
			(stroke
				(width 0.1524)
				(type default)
			)
			(layer "B.SilkS")
		)
		(fp_line
			(start 1.1049 -0.724916)
			(end 1.1049 0.724916)
			(stroke
				(width 0.1)
				(type default)
			)
			(layer "B.Fab")
		)
		(fp_line
			(start -1.1049 -0.724916)
			(end 1.1049 -0.724916)
			(stroke
				(width 0.1)
				(type default)
			)
			(layer "B.Fab")
		)
		(fp_line
			(start 1.1049 0.724916)
			(end -1.1049 0.724916)
			(stroke
				(width 0.1)
				(type default)
			)
			(layer "B.Fab")
		)
		(fp_line
			(start -1.1049 0.724916)
			(end -1.1049 -0.724916)
			(stroke
				(width 0.1)
				(type default)
			)
			(layer "B.Fab")
		)
		(pad "1" smd rect
			(at 0.889 0 90)
			(size 1.016 1.27)
			(layers "B.Cu" "B.Mask" "B.Paste")
			(net "SW_P12V_AUX_PVDDCR_CPU1_P1_FLT")
		)
		(pad "2" smd rect
			(at -0.889 0 90)
			(size 1.016 1.27)
			(layers "B.Cu" "B.Mask" "B.Paste")
			(net "GND")
		)
	)
	(footprint ""
		(layer "B.Cu")
		(at 298.054014 -347.77553 -90)
		(property "Reference" "PR100"
			(at 0 0 90)
			(layer "B.SilkS")
			(hide yes)
			(effects
				(font
					(size 1.27 1.27)
				)
				(justify mirror)
			)
		)
		(property "Value" ""
			(at 0 0 90)
			(layer "B.Fab")
			(effects
				(font
					(size 1.27 1.27)
				)
				(justify mirror)
			)
		)
		(duplicate_pad_numbers_are_jumpers no)
		(fp_line
			(start -0.7874 0.4064)
			(end 0.7874 0.4064)
			(stroke
				(width 0.1524)
				(type default)
			)
			(layer "B.SilkS")
		)
		(fp_line
			(start 0.7874 0.4064)
			(end 0.7874 -0.4064)
			(stroke
				(width 0.1524)
				(type default)
			)
			(layer "B.SilkS")
		)
		(fp_line
			(start -0.7874 -0.4064)
			(end -0.7874 0.4064)
			(stroke
				(width 0.1524)
				(type default)
			)
			(layer "B.SilkS")
		)
		(fp_line
			(start 0.7874 -0.4064)
			(end -0.7874 -0.4064)
			(stroke
				(width 0.1524)
				(type default)
			)
			(layer "B.SilkS")
		)
		(fp_line
			(start -0.67945 0.3048)
			(end -0.120396 0.3048)
			(stroke
				(width 0.1)
				(type default)
			)
			(layer "B.Fab")
		)
		(fp_line
			(start -0.120396 0.3048)
			(end -0.120396 0.2794)
			(stroke
				(width 0.1)
				(type default)
			)
			(layer "B.Fab")
		)
		(fp_line
			(start 0.12065 0.3048)
			(end 0.67945 0.3048)
			(stroke
				(width 0.1)
				(type default)
			)
			(layer "B.Fab")
		)
		(fp_line
			(start 0.67945 0.3048)
			(end 0.67945 -0.305054)
			(stroke
				(width 0.1)
				(type default)
			)
			(layer "B.Fab")
		)
		(fp_line
			(start -0.120396 0.2794)
			(end 0.12065 0.2794)
			(stroke
				(width 0.1)
				(type default)
			)
			(layer "B.Fab")
		)
		(fp_line
			(start 0.12065 0.2794)
			(end 0.12065 0.3048)
			(stroke
				(width 0.1)
				(type default)
			)
			(layer "B.Fab")
		)
		(fp_line
			(start -0.12065 -0.2794)
			(end -0.12065 -0.3048)
			(stroke
				(width 0.1)
				(type default)
			)
			(layer "B.Fab")
		)
		(fp_line
			(start 0.12065 -0.2794)
			(end -0.12065 -0.2794)
			(stroke
				(width 0.1)
				(type default)
			)
			(layer "B.Fab")
		)
		(fp_line
			(start -0.67945 -0.3048)
			(end -0.67945 0.3048)
			(stroke
				(width 0.1)
				(type default)
			)
			(layer "B.Fab")
		)
		(fp_line
			(start -0.12065 -0.3048)
			(end -0.67945 -0.3048)
			(stroke
				(width 0.1)
				(type default)
			)
			(layer "B.Fab")
		)
		(fp_line
			(start 0.12065 -0.305054)
			(end 0.12065 -0.2794)
			(stroke
				(width 0.1)
				(type default)
			)
			(layer "B.Fab")
		)
		(fp_line
			(start 0.67945 -0.305054)
			(end 0.12065 -0.305054)
			(stroke
				(width 0.1)
				(type default)
			)
			(layer "B.Fab")
		)
		(pad "1" smd circle
			(at 0.40005 0 90)
			(size 0 0)
			(layers "B.Cu" "B.Mask" "B.Paste")
			(net "PVDDCR_CPU1_P0_PVCC")
		)
		(pad "2" smd circle
			(at -0.40005 0 90)
			(size 0 0)
			(layers "B.Cu" "B.Mask" "B.Paste")
			(net "PVDDIO_P0_VCC1")
		)
	)
	(footprint ""
		(layer "B.Cu")
		(at 231.914192 -321.775582 180)
		(property "Reference" "R1260"
			(at 0 0 0)
			(layer "B.SilkS")
			(hide yes)
			(effects
				(font
					(size 1.27 1.27)
				)
				(justify mirror)
			)
		)
		(property "Value" ""
			(at 0 0 0)
			(layer "B.Fab")
			(effects
				(font
					(size 1.27 1.27)
				)
				(justify mirror)
			)
		)
		(duplicate_pad_numbers_are_jumpers no)
		(fp_line
			(start 0.7874 0.4064)
			(end 0.7874 -0.4064)
			(stroke
				(width 0.1524)
				(type default)
			)
			(layer "B.SilkS")
		)
		(fp_line
			(start 0.7874 -0.4064)
			(end -0.7874 -0.4064)
			(stroke
				(width 0.1524)
				(type default)
			)
			(layer "B.SilkS")
		)
		(fp_line
			(start -0.7874 0.4064)
			(end 0.7874 0.4064)
			(stroke
				(width 0.1524)
				(type default)
			)
			(layer "B.SilkS")
		)
		(fp_line
			(start -0.7874 -0.4064)
			(end -0.7874 0.4064)
			(stroke
				(width 0.1524)
				(type default)
			)
			(layer "B.SilkS")
		)
		(fp_line
			(start 0.67945 0.3048)
			(end 0.67945 -0.305054)
			(stroke
				(width 0.1)
				(type default)
			)
			(layer "B.Fab")
		)
		(fp_line
			(start 0.67945 -0.305054)
			(end 0.12065 -0.305054)
			(stroke
				(width 0.1)
				(type default)
			)
			(layer "B.Fab")
		)
		(fp_line
			(start 0.12065 0.3048)
			(end 0.67945 0.3048)
			(stroke
				(width 0.1)
				(type default)
			)
			(layer "B.Fab")
		)
		(fp_line
			(start 0.12065 0.2794)
			(end 0.12065 0.3048)
			(stroke
				(width 0.1)
				(type default)
			)
			(layer "B.Fab")
		)
		(fp_line
			(start 0.12065 -0.2794)
			(end -0.12065 -0.2794)
			(stroke
				(width 0.1)
				(type default)
			)
			(layer "B.Fab")
		)
		(fp_line
			(start 0.12065 -0.305054)
			(end 0.12065 -0.2794)
			(stroke
				(width 0.1)
				(type default)
			)
			(layer "B.Fab")
		)
		(fp_line
			(start -0.120396 0.3048)
			(end -0.120396 0.2794)
			(stroke
				(width 0.1)
				(type default)
			)
			(layer "B.Fab")
		)
		(fp_line
			(start -0.120396 0.2794)
			(end 0.12065 0.2794)
			(stroke
				(width 0.1)
				(type default)
			)
			(layer "B.Fab")
		)
		(fp_line
			(start -0.12065 -0.2794)
			(end -0.12065 -0.3048)
			(stroke
				(width 0.1)
				(type default)
			)
			(layer "B.Fab")
		)
		(fp_line
			(start -0.12065 -0.3048)
			(end -0.67945 -0.3048)
			(stroke
				(width 0.1)
				(type default)
			)
			(layer "B.Fab")
		)
		(fp_line
			(start -0.67945 0.3048)
			(end -0.120396 0.3048)
			(stroke
				(width 0.1)
				(type default)
			)
			(layer "B.Fab")
		)
		(fp_line
			(start -0.67945 -0.3048)
			(end -0.67945 0.3048)
			(stroke
				(width 0.1)
				(type default)
			)
			(layer "B.Fab")
		)
		(pad "1" smd rect
			(at 0.40005 0 180)
			(size 0.4572 0.508)
			(layers "B.Cu" "B.Mask" "B.Paste")
			(net "P5V_AUX_ADC")
		)
		(pad "2" smd rect
			(at -0.40005 0 180)
			(size 0.4572 0.508)
			(layers "B.Cu" "B.Mask" "B.Paste")
			(net "P5V_AUX_ADC_MAM")
		)
	)
	(footprint ""
		(layer "B.Cu")
		(at 77.14488 -11.267948 90)
		(property "Reference" "R3168"
			(at 0 0 90)
			(layer "B.SilkS")
			(hide yes)
			(effects
				(font
					(size 1.27 1.27)
				)
				(justify mirror)
			)
		)
		(property "Value" ""
			(at 0 0 90)
			(layer "B.Fab")
			(effects
				(font
					(size 1.27 1.27)
				)
				(justify mirror)
			)
		)
		(duplicate_pad_numbers_are_jumpers no)
		(fp_line
			(start 0.7874 -0.4064)
			(end -0.7874 -0.4064)
			(stroke
				(width 0.1524)
				(type default)
			)
			(layer "B.SilkS")
		)
		(fp_line
			(start -0.7874 -0.4064)
			(end -0.7874 0.4064)
			(stroke
				(width 0.1524)
				(type default)
			)
			(layer "B.SilkS")
		)
		(fp_line
			(start 0.7874 0.4064)
			(end 0.7874 -0.4064)
			(stroke
				(width 0.1524)
				(type default)
			)
			(layer "B.SilkS")
		)
		(fp_line
			(start -0.7874 0.4064)
			(end 0.7874 0.4064)
			(stroke
				(width 0.1524)
				(type default)
			)
			(layer "B.SilkS")
		)
		(fp_line
			(start 0.67945 -0.305054)
			(end 0.12065 -0.305054)
			(stroke
				(width 0.1)
				(type default)
			)
			(layer "B.Fab")
		)
		(fp_line
			(start 0.12065 -0.305054)
			(end 0.12065 -0.2794)
			(stroke
				(width 0.1)
				(type default)
			)
			(layer "B.Fab")
		)
		(fp_line
			(start -0.12065 -0.3048)
			(end -0.67945 -0.3048)
			(stroke
				(width 0.1)
				(type default)
			)
			(layer "B.Fab")
		)
		(fp_line
			(start -0.67945 -0.3048)
			(end -0.67945 0.3048)
			(stroke
				(width 0.1)
				(type default)
			)
			(layer "B.Fab")
		)
		(fp_line
			(start 0.12065 -0.2794)
			(end -0.12065 -0.2794)
			(stroke
				(width 0.1)
				(type default)
			)
			(layer "B.Fab")
		)
		(fp_line
			(start -0.12065 -0.2794)
			(end -0.12065 -0.3048)
			(stroke
				(width 0.1)
				(type default)
			)
			(layer "B.Fab")
		)
		(fp_line
			(start 0.12065 0.2794)
			(end 0.12065 0.3048)
			(stroke
				(width 0.1)
				(type default)
			)
			(layer "B.Fab")
		)
		(fp_line
			(start -0.120396 0.2794)
			(end 0.12065 0.2794)
			(stroke
				(width 0.1)
				(type default)
			)
			(layer "B.Fab")
		)
		(fp_line
			(start 0.67945 0.3048)
			(end 0.67945 -0.305054)
			(stroke
				(width 0.1)
				(type default)
			)
			(layer "B.Fab")
		)
		(fp_line
			(start 0.12065 0.3048)
			(end 0.67945 0.3048)
			(stroke
				(width 0.1)
				(type default)
			)
			(layer "B.Fab")
		)
		(fp_line
			(start -0.120396 0.3048)
			(end -0.120396 0.2794)
			(stroke
				(width 0.1)
				(type default)
			)
			(layer "B.Fab")
		)
		(fp_line
			(start -0.67945 0.3048)
			(end -0.120396 0.3048)
			(stroke
				(width 0.1)
				(type default)
			)
			(layer "B.Fab")
		)
		(pad "1" smd circle
			(at 0.40005 0 270)
			(size 0 0)
			(layers "B.Cu" "B.Mask" "B.Paste")
			(net "OCP_V3_2_MAIN_PWR_EN")
		)
		(pad "2" smd circle
			(at -0.40005 0 270)
			(size 0 0)
			(layers "B.Cu" "B.Mask" "B.Paste")
			(net "OCP_V3_2_MAIN_PWR_EN_R")
		)
	)
	(footprint ""
		(layer "B.Cu")
		(at 171.196 -110.200948)
		(property "Reference" "R168"
			(at 0 0 0)
			(layer "B.SilkS")
			(hide yes)
			(effects
				(font
					(size 1.27 1.27)
				)
				(justify mirror)
			)
		)
		(property "Value" ""
			(at 0 0 0)
			(layer "B.Fab")
			(effects
				(font
					(size 1.27 1.27)
				)
				(justify mirror)
			)
		)
		(duplicate_pad_numbers_are_jumpers no)
		(fp_line
			(start -0.7874 -0.4064)
			(end -0.7874 0.4064)
			(stroke
				(width 0.1524)
				(type default)
			)
			(layer "B.SilkS")
		)
		(fp_line
			(start -0.7874 0.4064)
			(end 0.7874 0.4064)
			(stroke
				(width 0.1524)
				(type default)
			)
			(layer "B.SilkS")
		)
		(fp_line
			(start 0.7874 -0.4064)
			(end -0.7874 -0.4064)
			(stroke
				(width 0.1524)
				(type default)
			)
			(layer "B.SilkS")
		)
		(fp_line
			(start 0.7874 0.4064)
			(end 0.7874 -0.4064)
			(stroke
				(width 0.1524)
				(type default)
			)
			(layer "B.SilkS")
		)
		(fp_line
			(start -0.67945 -0.3048)
			(end -0.67945 0.3048)
			(stroke
				(width 0.1)
				(type default)
			)
			(layer "B.Fab")
		)
		(fp_line
			(start -0.67945 0.3048)
			(end -0.120396 0.3048)
			(stroke
				(width 0.1)
				(type default)
			)
			(layer "B.Fab")
		)
		(fp_line
			(start -0.12065 -0.3048)
			(end -0.67945 -0.3048)
			(stroke
				(width 0.1)
				(type default)
			)
			(layer "B.Fab")
		)
		(fp_line
			(start -0.12065 -0.2794)
			(end -0.12065 -0.3048)
			(stroke
				(width 0.1)
				(type default)
			)
			(layer "B.Fab")
		)
		(fp_line
			(start -0.120396 0.2794)
			(end 0.12065 0.2794)
			(stroke
				(width 0.1)
				(type default)
			)
			(layer "B.Fab")
		)
		(fp_line
			(start -0.120396 0.3048)
			(end -0.120396 0.2794)
			(stroke
				(width 0.1)
				(type default)
			)
			(layer "B.Fab")
		)
		(fp_line
			(start 0.12065 -0.305054)
			(end 0.12065 -0.2794)
			(stroke
				(width 0.1)
				(type default)
			)
			(layer "B.Fab")
		)
		(fp_line
			(start 0.12065 -0.2794)
			(end -0.12065 -0.2794)
			(stroke
				(width 0.1)
				(type default)
			)
			(layer "B.Fab")
		)
		(fp_line
			(start 0.12065 0.2794)
			(end 0.12065 0.3048)
			(stroke
				(width 0.1)
				(type default)
			)
			(layer "B.Fab")
		)
		(fp_line
			(start 0.12065 0.3048)
			(end 0.67945 0.3048)
			(stroke
				(width 0.1)
				(type default)
			)
			(layer "B.Fab")
		)
		(fp_line
			(start 0.67945 -0.305054)
			(end 0.12065 -0.305054)
			(stroke
				(width 0.1)
				(type default)
			)
			(layer "B.Fab")
		)
		(fp_line
			(start 0.67945 0.3048)
			(end 0.67945 -0.305054)
			(stroke
				(width 0.1)
				(type default)
			)
			(layer "B.Fab")
		)
		(pad "1" smd circle
			(at 0.40005 0 180)
			(size 0 0)
			(layers "B.Cu" "B.Mask" "B.Paste")
			(net "SGPIO_SCM_DI_R<1>")
		)
		(pad "2" smd circle
			(at -0.40005 0 180)
			(size 0 0)
			(layers "B.Cu" "B.Mask" "B.Paste")
			(net "SGPIO_SCM_DI_<1>")
		)
	)
)
